#ISCELL
  pure_quanta quanta_title_block_c *
  *
#CELL
  pure_quanta q_res *
  page83_i100
#ISCELL
  standard offpage *
  page83_i13
#ISCELL
  standard offpage *
  page83_i14
#ISCELL
  pure_quanta_power universal_power *
  page83_i17
#CELL
  pure_quanta q_res *
  page83_i18
#CELL
  pure_quanta q_res *
  page83_i181
#ISCELL
  pure_quanta_power universal_power *
  page83_i182
#ISCELL
  pure_quanta_power universal_power *
  page83_i183
#CELL
  pure_quanta q_res *
  page83_i184
#ISCELL
  pure_quanta_power universal_power *
  page83_i185
#ISCELL
  pure_quanta_power universal_power *
  page83_i186
#ISCELL
  standard offpage *
  page83_i187
#CELL
  pure_quanta q_res *
  page83_i188
#CELL
  pure_quanta q_res *
  page83_i189
#CELL
  pure_quanta q_res *
  page83_i19
#CELL
  pure_quanta q_res *
  page83_i190
#CELL
  pure_quanta q_res *
  page83_i191
#ISCELL
  standard offpage *
  page83_i192
#ISCELL
  standard offpage *
  page83_i193
#ISCELL
  standard offpage *
  page83_i194
#CELL
  pure_quanta q_res *
  page83_i195
#ISCELL
  pure_quanta_power universal_power *
  page83_i196
#CELL
  pure_quanta q_res *
  page83_i197
#CELL
  pure_quanta mosfet_n *
  page83_i198
#ISCELL
  pure_quanta_power universal_gnd *
  page83_i199
#ISCELL
  pure_quanta_power universal_power *
  page83_i20
#ISCELL
  pure_quanta_power universal_power *
  page83_i200
#CELL
  pure_quanta q_res *
  page83_i201
#ISCELL
  standard offpage *
  page83_i202
#CELL
  pure_quanta q_res *
  page83_i203
#ISCELL
  pure_quanta_power universal_gnd *
  page83_i204
#CELL
  pure_quanta q_res *
  page83_i205
#ISCELL
  pure_quanta_power universal_gnd *
  page83_i206
#CELL
  pure_quanta q_res *
  page83_i21
#CELL
  pure_quanta q_res *
  page83_i22
#CELL
  pure_quanta sn74lvc1g07dbvr *
  page83_i23
#ISCELL
  pure_quanta_power universal_gnd *
  page83_i24
#CELL
  pure_quanta sn74lvc1g07dbvr *
  page83_i25
#ISCELL
  pure_quanta_power universal_power *
  page83_i26
#ISCELL
  pure_quanta_power universal_gnd *
  page83_i27
#CELL
  pure_quanta q_cap *
  page83_i28
#ISCELL
  pure_quanta_power universal_power *
  page83_i30
#CELL
  pure_quanta q_cap *
  page83_i31
#ISCELL
  pure_quanta_power universal_gnd *
  page83_i32
#ISCELL
  standard offpage *
  page83_i34
#ISCELL
  standard offpage *
  page83_i35
#ISCELL
  pure_quanta_power universal_gnd *
  page83_i36
#ISCELL
  pure_quanta_power universal_power *
  page83_i37
#CELL
  pure_quanta q_res *
  page83_i39
#CELL
  pure_quanta mosfet_n_gsd *
  page83_i40
#CELL
  pure_quanta q_res *
  page83_i41
#ISCELL
  standard offpage *
  page83_i42
#CELL
  pure_quanta q_res *
  page83_i45
#ISCELL
  pure_quanta_power universal_gnd *
  page83_i46
#CELL
  pure_quanta mosfet_n_gsd *
  page83_i47
#CELL
  pure_quanta q_res *
  page83_i48
#ISCELL
  pure_quanta_power universal_gnd *
  page83_i49
#ISCELL
  standard offpage *
  page83_i50
#ISCELL
  pure_quanta_power vcc_core *
  page83_i51
#CELL
  pure_quanta q_res *
  page83_i52
#ISCELL
  standard offpage *
  page83_i53
#ISCELL
  standard offpage *
  page83_i54
#CELL
  pure_quanta q_res *
  page83_i55
#ISCELL
  pure_quanta_power vcc_core *
  page83_i59
#ISCELL
  pure_quanta_power gnd *
  page83_i60
#CELL
  pure_quanta mosfet_dual_6p *
  page83_i61
#ISCELL
  pure_quanta_power gnd *
  page83_i62
#CELL
  pure_quanta q_res *
  page83_i63
#ISCELL
  pure_quanta_power gnd *
  page83_i64
#CELL
  pure_quanta sn74lvc1g07dbvr *
  page83_i65
#ISCELL
  pure_quanta_power universal_gnd *
  page83_i66
#CELL
  pure_quanta q_res *
  page83_i67
#ISCELL
  pure_quanta_power universal_power *
  page83_i68
#ISCELL
  standard offpage *
  page83_i69
#ISCELL
  standard offpage *
  page83_i70
#ISCELL
  pure_quanta_power universal_gnd *
  page83_i71
#CELL
  pure_quanta q_cap *
  page83_i72
#CELL
  pure_quanta q_res *
  page83_i73
#ISCELL
  standard offpage *
  page83_i74
#CELL
  pure_quanta sn74lvc1g07dbvr *
  page83_i83
#ISCELL
  pure_quanta_power universal_power *
  page83_i84
#CELL
  pure_quanta q_cap *
  page83_i85
#ISCELL
  pure_quanta_power universal_gnd *
  page83_i86
#CELL
  pure_quanta q_res *
  page83_i87
#ISCELL
  pure_quanta_power universal_gnd *
  page83_i88
#ISCELL
  standard offpage *
  page83_i89
#ISCELL
  standard offpage *
  page83_i90
#ISCELL
  standard offpage *
  page83_i91
#ISCELL
  standard offpage *
  page83_i92
#ISCELL
  standard offpage *
  page83_i93
#ISCELL
  standard offpage *
  page83_i94
#CELL
  pure_quanta q_res *
  page83_i96
#CELL
  pure_quanta q_res *
  page83_i97
#CELL
  pure_quanta q_res *
  page83_i98
#CELL
  pure_quanta q_res *
  page83_i99
